# TIMECARD (Time Appliance Project (Time Card)) — schematic netlist excerpt (pin names and nets, part order shuffled) for the footprints in the layout excerpt that follows; sources: Cadence DE-HDL packaged netlist, KiCad conversion of R4006-B0001-02_R01.brd

R329  RESISTOR  33OHM 1%  pkg SMC_0402R_H016  page 25 : \1\ = FPGA_IO_7 ; \2\ = UNNAMED_16_CONNHDR2X6FSSMT_I1_4
C139  CAPACITOR  0.1UF 10V 10%  pkg SMC_0402R_H022  page 14 : \1\ = XP3R3V_FPGA ; \2\ = SG

(kicad_pcb
	(version 20260206)
	(generator "pcbnew")
	(generator_version "10.0")
	(general
		(thickness 1.6)
		(legacy_teardrops no)
	)
	(paper "A4")
	(title_block
		(title "timecard-production-celestica-r4006 — R4006-B0001-02_R01.brd")
		(comment 1 "Time Appliance Project (Time Card) / footprints 905-906 of 1113")
	)
	(layers
		(0 "F.Cu" signal "TOP")
		(4 "In1.Cu" signal "L02_GND1")
		(6 "In2.Cu" signal "L03_SIG1")
		(8 "In3.Cu" signal "L04_GND2")
		(10 "In4.Cu" signal "L05_VCC1")
		(12 "In5.Cu" signal "L06_VCC2")
		(14 "In6.Cu" signal "L07_GND3")
		(16 "In7.Cu" signal "L08_SIG2")
		(18 "In8.Cu" signal "L09_GND4")
		(2 "B.Cu" signal "BOTTOM")
		(9 "F.Adhes" user "F.Adhesive")
		(11 "B.Adhes" user "B.Adhesive")
		(13 "F.Paste" user "Package Geometry/Pastemask Top")
		(15 "B.Paste" user "Package Geometry/Pastemask Bottom")
		(5 "F.SilkS" user "Ref Des/Silkscreen Top")
		(7 "B.SilkS" user "Ref Des/Silkscreen Bottom")
		(1 "F.Mask" user "Board Geometry/Soldermask Top")
		(3 "B.Mask" user "Board Geometry/Soldermask Bottom")
		(17 "Dwgs.User" user "User.Drawings")
		(19 "Cmts.User" user "User.Comments")
		(21 "Eco1.User" user "User.Eco1")
		(23 "Eco2.User" user "User.Eco2")
		(25 "Edge.Cuts" user "Board Geometry/Outline")
		(27 "Margin" user)
		(31 "F.CrtYd" user "Package Geometry/Place Bound Top")
		(29 "B.CrtYd" user "Package Geometry/Place Bound Bottom")
		(35 "F.Fab" user "Ref Des/Assembly Top")
		(33 "B.Fab" user "Ref Des/Assembly Bottom")
	)
	(footprint ""
		(layer "B.Cu")
		(at 118.347236 -45.823124 180)
		(property "Reference" "C139"
			(at -2.302764 -1.277874 0)
			(unlocked yes)
			(layer "B.SilkS")
			(effects
				(font
					(size 0.635 0.4064)
					(thickness 0.1524)
				)
				(justify mirror)
			)
		)
		(property "Value" "VAL*"
			(at 0 3.718306 180)
			(unlocked yes)
			(layer "B.Fab")
			(hide yes)
			(effects
				(font
					(size 0.7874 0.5842)
					(thickness 0.127)
				)
				(justify mirror)
			)
		)
		(property "Tolerance" "TOL*"
			(at 0 4.861306 180)
			(unlocked yes)
			(layer "Cmts.User")
			(hide yes)
			(effects
				(font
					(size 0.7874 0.5842)
					(thickness 0.127)
				)
				(justify mirror)
			)
		)
		(property "User Part Number" "PARTNUM*"
			(at 0 2.575306 180)
			(unlocked yes)
			(layer "Cmts.User")
			(hide yes)
			(effects
				(font
					(size 0.7874 0.5842)
					(thickness 0.127)
				)
				(justify mirror)
			)
		)
		(property "Device Type" "CAPACITOR-G105-0B104-CK,0.1UF,A"
			(at 0 1.432306 180)
			(unlocked yes)
			(layer "B.Fab")
			(hide yes)
			(effects
				(font
					(size 0.7874 0.5842)
					(thickness 0.127)
				)
				(justify mirror)
			)
		)
		(duplicate_pad_numbers_are_jumpers no)
		(fp_line
			(start 0.970026 0.4699)
			(end 0.970026 -0.4699)
			(stroke
				(width 0.1)
				(type default)
			)
			(layer "B.SilkS")
		)
		(fp_line
			(start 0.970026 -0.4699)
			(end -0.970026 -0.4699)
			(stroke
				(width 0.1)
				(type default)
			)
			(layer "B.SilkS")
		)
		(fp_line
			(start -0.970026 0.4699)
			(end 0.970026 0.4699)
			(stroke
				(width 0.1)
				(type default)
			)
			(layer "B.SilkS")
		)
		(fp_line
			(start -0.970026 -0.4699)
			(end -0.970026 0.4699)
			(stroke
				(width 0.1)
				(type default)
			)
			(layer "B.SilkS")
		)
		(fp_poly
			(pts
				(xy 0.970026 0.4699) (xy -0.970026 0.4699) (xy -0.970026 -0.4699) (xy 0.970026 -0.4699)
			)
			(stroke
				(width 0)
				(type default)
			)
			(fill no)
			(layer "B.CrtYd")
		)
		(fp_line
			(start 0.508 0.3048)
			(end 0.508 -0.3048)
			(stroke
				(width 0.1)
				(type default)
			)
			(layer "B.Fab")
		)
		(fp_line
			(start 0.508 -0.3048)
			(end -0.508 -0.3048)
			(stroke
				(width 0.1)
				(type default)
			)
			(layer "B.Fab")
		)
		(fp_line
			(start -0.508 0.3048)
			(end 0.508 0.3048)
			(stroke
				(width 0.1)
				(type default)
			)
			(layer "B.Fab")
		)
		(fp_line
			(start -0.508 -0.3048)
			(end -0.508 0.3048)
			(stroke
				(width 0.1)
				(type default)
			)
			(layer "B.Fab")
		)
		(pad "1" smd circle
			(at 0.500126 0)
			(size 0.635 0.635)
			(layers "B.Cu" "B.Mask" "B.Paste")
			(net "XP3R3V_FPGA")
		)
		(pad "2" smd circle
			(at -0.500126 0)
			(size 0.635 0.635)
			(layers "B.Cu" "B.Mask" "B.Paste")
			(net "SG")
		)
	)
	(footprint ""
		(layer "B.Cu")
		(at 156.718 -36.957 -90)
		(property "Reference" "R329"
			(at 5.24637 0.635 0)
			(unlocked yes)
			(layer "B.SilkS")
			(effects
				(font
					(size 0.7874 0.5842)
					(thickness 0.1524)
				)
				(justify mirror)
			)
		)
		(property "Value" "VAL*"
			(at -0.02032 2.13233 270)
			(unlocked yes)
			(layer "B.Fab")
			(hide yes)
			(effects
				(font
					(size 0.7874 0.5842)
					(thickness 0.1524)
				)
				(justify mirror)
			)
		)
		(property "Tolerance" "TOL*"
			(at -0.044704 3.05435 270)
			(unlocked yes)
			(layer "Cmts.User")
			(hide yes)
			(effects
				(font
					(size 0.7874 0.5842)
					(thickness 0.1524)
				)
				(justify mirror)
			)
		)
		(property "User Part Number" "PARTNUM*"
			(at -0.02032 4.024884 270)
			(unlocked yes)
			(layer "Cmts.User")
			(hide yes)
			(effects
				(font
					(size 0.7874 0.5842)
					(thickness 0.1524)
				)
				(justify mirror)
			)
		)
		(property "Device Type" "RESISTOR-G155-133R0-01,33OHM,1%"
			(at -0.008382 1.210564 270)
			(unlocked yes)
			(layer "B.Fab")
			(hide yes)
			(effects
				(font
					(size 0.7874 0.5842)
					(thickness 0.1524)
				)
				(justify mirror)
			)
		)
		(duplicate_pad_numbers_are_jumpers no)
		(fp_line
			(start -1.143 0.5588)
			(end -1.143 -0.5588)
			(stroke
				(width 0.1)
				(type default)
			)
			(layer "B.SilkS")
		)
		(fp_line
			(start 1.143 0.5588)
			(end -1.143 0.5588)
			(stroke
				(width 0.1)
				(type default)
			)
			(layer "B.SilkS")
		)
		(fp_line
			(start -1.143 -0.5588)
			(end 1.143 -0.5588)
			(stroke
				(width 0.1)
				(type default)
			)
			(layer "B.SilkS")
		)
		(fp_line
			(start 1.143 -0.5588)
			(end 1.143 0.5588)
			(stroke
				(width 0.1)
				(type default)
			)
			(layer "B.SilkS")
		)
		(fp_poly
			(pts
				(xy 1.143 0.5588) (xy -1.143 0.5588) (xy -1.143 -0.5588) (xy 1.143 -0.5588)
			)
			(stroke
				(width 0)
				(type default)
			)
			(fill no)
			(layer "B.CrtYd")
		)
		(fp_line
			(start -0.508 0.3048)
			(end -0.508 -0.3048)
			(stroke
				(width 0.1)
				(type default)
			)
			(layer "B.Fab")
		)
		(fp_line
			(start 0.508 0.3048)
			(end -0.508 0.3048)
			(stroke
				(width 0.1)
				(type default)
			)
			(layer "B.Fab")
		)
		(fp_line
			(start -0.508 -0.3048)
			(end 0.508 -0.3048)
			(stroke
				(width 0.1)
				(type default)
			)
			(layer "B.Fab")
		)
		(fp_line
			(start 0.508 -0.3048)
			(end 0.508 0.3048)
			(stroke
				(width 0.1)
				(type default)
			)
			(layer "B.Fab")
		)
		(pad "1" smd rect
			(at 0.5334 0 90)
			(size 0.7112 0.6096)
			(layers "B.Cu" "B.Mask" "B.Paste")
			(net "FPGA_IO_7")
		)
		(pad "2" smd rect
			(at -0.5334 0 90)
			(size 0.7112 0.6096)
			(layers "B.Cu" "B.Mask" "B.Paste")
			(net "UNNAMED_16_CONNHDR2X6FSSMT_I1_4")
		)
		(zone
			(layer "B.Cu")
			(hatch none 0.5)
			(connect_pads
				(clearance 0)
			)
			(min_thickness 0.25)
			(keepout
				(tracks not_allowed)
				(vias allowed)
				(pads allowed)
				(copperpour not_allowed)
				(footprints allowed)
			)
			(placement
				(enabled no)
				(sheetname "")
			)
			(fill
				(thermal_gap 0.5)
				(thermal_bridge_width 0.5)
				(island_removal_mode 0)
			)
			(polygon
				(pts
					(xy 156.4132 -36.8808) (xy 157.0228 -36.8808) (xy 157.0228 -37.0332) (xy 156.4132 -37.0332)
				)
			)
		)
		(zone
			(layer "B.Cu")
			(hatch none 0.5)
			(connect_pads
				(clearance 0)
			)
			(min_thickness 0.25)
			(keepout
				(tracks allowed)
				(vias not_allowed)
				(pads allowed)
				(copperpour not_allowed)
				(footprints allowed)
			)
			(placement
				(enabled no)
				(sheetname "")
			)
			(fill
				(thermal_gap 0.5)
				(thermal_bridge_width 0.5)
				(island_removal_mode 0)
			)
			(polygon
				(pts
					(xy 156.4132 -36.8808) (xy 157.0228 -36.8808) (xy 157.0228 -37.0332) (xy 156.4132 -37.0332)
				)
			)
		)
	)
)
